FILE_TYPE=LIBRARY_PARTS;
TIME=' Created/Modified on Mon Sep 16 10:22:17 2002' ;
PRIMITIVE 'INDUCTOR','INDUCTOR_SMLF','INDUCTOR_THLF';
  pin
    'INA':
      PIN_NUMBER='(1)';
      PINUSE='UNSPEC';
      NO_LOAD_CHECK='BOTH';
      NO_IO_CHECK='BOTH';
      ALLOW_CONNECT='TRUE';
      PIN_GROUP='0';
    'INB':
      PIN_NUMBER='(2)';
      PINUSE='UNSPEC';
      NO_LOAD_CHECK='BOTH';
      NO_IO_CHECK='BOTH';
      ALLOW_CONNECT='TRUE';
      PIN_GROUP='0';
  end_pin;
 BODY
  BODY_NAME='INDUCTOR';
  PART_NAME='INDUCTOR';
  PHYS_DES_PREFIX='L';
 END_BODY;
 END_PRIMITIVE;


PRIMITIVE 'INDUCTOR_DUALLF';
     PIN	
    'A1':
      PIN_NUMBER='(1)';
      PIN_TYPE='ANALOG';
      NO_LOAD_CHECK='BOTH';
      NO_IO_CHECK='BOTH';
      ALLOW_CONNECT='TRUE';
    'A2':
      PIN_NUMBER='(2)';
      PIN_TYPE='ANALOG';
      NO_LOAD_CHECK='BOTH';
      NO_IO_CHECK='BOTH';
      ALLOW_CONNECT='TRUE';
    'B1':
      PIN_NUMBER='(3)';
      PIN_TYPE='ANALOG';
      NO_LOAD_CHECK='BOTH';
      NO_IO_CHECK='BOTH';
      ALLOW_CONNECT='TRUE';
    'B2':
      PIN_NUMBER='(4)';
      PIN_TYPE='ANALOG';
      NO_LOAD_CHECK='BOTH';
      NO_IO_CHECK='BOTH';
      ALLOW_CONNECT='TRUE';
  end_pin;
  BODY
  BODY_NAME='INDUCTOR';
  PART_NAME='INDUCTOR';
  PHYS_DES_PREFIX='L';
 END_BODY;
 END_PRIMITIVE;

END.
